FILE_TYPE = CONNECTIVITY;
{Allegro Design Entry HDL 16.6-p007 (v16-6-112F) 10/10/2012}
"PAGE_NUMBER" = 210;
0"NC";
1"GND\g";
2"GND\g";
3"VR_FET_SW_P12V_STBY_PVCCIN_CPU1\g";
4"GND\g";
5"GND\g";
6"P5V_STBY\g";
7"PVSA_CPU1\g";
8"PVSA_CPU1\g";
9"GND\g";
10"GND\g";
11"GND\g";
12"GND\g";
13"PVSA_CPU1\g";
14"GND\g";
15"VR_PVSA_CPU1_PHASE_SW"VOLTAGE"5";
16"TP_PVSA_CPU1_GL_0";
17"TP_PVSA_CPU1_GL_1";
18"VR_PVSA_CPU1_VCIN"VOLTAGE"5";
19"VSENSE_PVSA_CPU1_N";
20"VSENSE_PVSA_CPU1_SKT_VRTN";
21"VR_PVSA_CPU1_BOOT";
22"VSENSE_PVSA_CPU1_P";
23"VSENSE_PVSA_CPU1_SKT_VSEN";
24"VR_PVSA_CPU1_BIREF1";
25"VR_PVSA_CPU1_BOOT_R";
26"VR_PVSA_CPU1_PHASE"VOLTAGE"5";
27"VR_PVSA_CPU1_OCSET";
28"ISENSE_PVSA_CPU1_IMON";
29"A_TSENSE_PVSA_CPU1";
30"VR_PVSA_CPU1_PWM";
31"VR_PVSA_CPU1_PHASE_SW_RC";
%"CAPP"
"1","(-1350,1450)","0","mstr_discrete","I12";
;
CDS_SEC"1"
LOCATION"C9N11"
VALUE"470UF"
TOLERANCE"20%"
PACK_TYPE"3018"
PART_NUMBER"699013-049"
MATERIAL"ALUM"
VOLTAGE"2.5V"
GROUP"PWR_BULK_CAP"
SEC"1"
SEC_TYPE"3018"
BOM_COST"PROC_VRD_VCCIN_CPU0"
ROOM"PVSA_CPU1_DECAP_VR"
CDS_LOCATION"C9N11"
CDS_LIB"mstr_discrete";
"B"
$PN"2"1;
"A"
$PN"1"8;
%"GND"
"1","(-1900,1075)","0","mstr_symbols","I13";
;
BOM_COST"PROC_VRD_VCCIN_CPU0"
ROOM"PVSA_CPU1_DECAP_VR"
VOLTAGE"0"
SIZE"1B"
CDS_LIB"mstr_symbols"
BODY_TYPE"PLUMBING"
HDL_POWER"GND";
"A\NAC"1;
%"CAPP"
"1","(-1900,1450)","2","mstr_discrete","I14";
;
CDS_SEC"1"
TOLERANCE"20%"
VOLTAGE"2.5V"
MATERIAL"ALUM"
PACK_TYPE"3018"
LOCATION"C9N20"
VALUE"470UF"
PART_NUMBER"699013-049"
GROUP"PWR_BULK_CAP"
CDS_LIB"mstr_discrete"
CDS_LOCATION"C9N20"
SEC"1"
SEC_TYPE"3018"
BOM_COST"PROC_VRD_VCCIN_CPU0"
ROOM"PVSA_CPU1_DECAP_VR";
"B"
$PN"2"1;
"A"
$PN"1"8;
%"GND"
"1","(-3100,2900)","0","mstr_symbols","I15";
;
ROOM"PVSA_CPU1_PWR_VR"
BOM_COST"PROC_VRD_VCCIN_CPU0"
CDS_LIB"mstr_symbols"
VOLTAGE"0"
SIZE"1B"
BODY_TYPE"PLUMBING"
HDL_POWER"GND";
"A\NAC"2;
%"VCC_CORE"
"1","(-6700,4250)","0","mstr_symbols","I21";
;
HDL_POWER"VR_FET_SW_P12V_STBY_PVCCIN_CPU1"
CDS_LIB"mstr_symbols";
"A"3;
%"CAP"
"1","(-5200,3850)","0","mstr_discrete","I22";
;
CDS_SEC"1"
PART_NUMBER"A36096-155"
PACK_TYPE"0402"
MATERIAL"X7R"
VALUE"0.22UF"
VOLTAGE"16V"
TOLERANCE"10%"
LOCATION"C1C4"
CDS_LIB"mstr_discrete"
SEC_TYPE"0402"
SEC"1"
CDS_LOCATION"C1C4"
ROOM"PVSA_CPU1_PWR_VR";
"A"
$PN"1"6;
"B"
$PN"2"5;
%"CAP"
"1","(-6125,3250)","2","mstr_discrete","I24";
;
CDS_SEC"1"
LOCATION"C1C12"
VALUE"0.220UF"
VOLTAGE"16V"
MATERIAL"X7R"
PACK_TYPE"0402"
TOLERANCE"10%"
PART_NUMBER"A36096-104"
CDS_LIB"mstr_discrete"
SEC_TYPE"0402"
ROOM"PVSA_CPU1_PWR_VR"
SPOF"TRUE"
SEC"1"
CDS_LOCATION"C1C12";
"A"
$PN"1"21;
"B"
$PN"2"26;
%"CAP"
"1","(-5875,3825)","0","mstr_discrete","I26";
;
CDS_SEC"1"
LOCATION"C1C5"
VALUE"1.0UF"
PACK_TYPE"0402"
MATERIAL"X6S"
PART_NUMBER"D97712-011"
VOLTAGE"16V"
TOLERANCE"10%"
ROOM"PVSA_CPU1_PWR_VR"
CDS_LOCATION"C1C5"
SEC"1"
SEC_TYPE"0402"
CDS_LIB"mstr_discrete";
"A"
$PN"1"18;
"B"
$PN"2"5;
%"CAP_A"
"1","(-6125,3850)","0","dev_discrete","I27";
;
LOCATION"C1C17"
PART_NUMBER"A36096-030"
VOLTAGE"16V"
PACK_TYPE"0402V"
VALUE"0.1UF"
TOLERANCE"10%"
MATERIAL"X7R"
CDS_LIB"dev_discrete"
CDS_LOCATION"C1C17"
ROOM"PVSA_CPU1_PWR_VR"
CDS_SEC"1"
SEC_TYPE"0402V"
SEC"1";
"B"
$PN"2"5;
"A"
$PN"1"3;
%"CAP"
"1","(-6375,3825)","0","mstr_discrete","I28";
;
CDS_SEC"1"
VALUE"1.0UF"
PART_NUMBER"D97712-011"
PACK_TYPE"0402"
MATERIAL"X6S"
TOLERANCE"10%"
VOLTAGE"16V"
LOCATION"C1C15"
CDS_LIB"mstr_discrete"
CDS_LOCATION"C1C15"
SEC_TYPE"0402"
SEC"1"
ROOM"PVSA_CPU1_PWR_VR";
"A"
$PN"1"3;
"B"
$PN"2"5;
%"RES"
"1","(-5300,2325)","0","mstr_discrete","I29";
;
CDS_SEC"1"
PART_NUMBER"G21796-017"
LOCATION"R1C12"
WATTAGE"1/16W"
VALUE"100.0"
PACK_TYPE"0402"
TOLERANCE"1%"
MATERIAL"CHIP"
BOM_COST"PROC_VRD_VCCIN_CPU0"
CDS_LIB"mstr_discrete"
ROOM"PVSA_CPU1_VSENSE_VR"
CDS_LOCATION"R1C12"
SEC"1"
SEC_TYPE"0402";
"B"
$PN"2"7;
"A"
$PN"1"22;
%"GND"
"1","(-4450,950)","0","mstr_symbols","I30";
;
SIZE"1B"
CDS_LIB"mstr_symbols"
VOLTAGE"0"
BOM_COST"PROC_VRD_VCCIN_CPU0"
ROOM"PVSA_CPU1_VSENSE_VR"
BODY_TYPE"PLUMBING"
HDL_POWER"GND";
"A\NAC"4;
%"RES"
"1","(-5275,1925)","0","mstr_discrete","I31";
;
CDS_SEC"1"
WATTAGE"1/16W"
PACK_TYPE"0402"
VALUE"0.0"
MATERIAL"CHIP"
LOCATION"R1C7"
TOLERANCE"5%"
PART_NUMBER"G21497-005"
CDS_LIB"mstr_discrete"
CDS_LOCATION"R1C7"
ROOM"PVSA_CPU1_VSENSE_VR"
BOM_COST"PROC_VRD_VCCIN_CPU0"
SEC"1"
SEC_TYPE"0402";
"B"
$PN"2"23;
"A"
$PN"1"22;
%"RES"
"1","(-5275,1475)","0","mstr_discrete","I32";
;
CDS_SEC"1"
PACK_TYPE"0402"
MATERIAL"CHIP"
PART_NUMBER"G21497-005"
LOCATION"R1C5"
TOLERANCE"5%"
WATTAGE"1/16W"
VALUE"0.0"
CDS_LIB"mstr_discrete"
CDS_LOCATION"R1C5"
BOM_COST"PROC_VRD_VCCIN_CPU0"
ROOM"PVSA_CPU1_VSENSE_VR"
SEC"1"
SEC_TYPE"0402";
"B"
$PN"2"20;
"A"
$PN"1"19;
%"RES"
"1","(-5275,1100)","0","mstr_discrete","I33";
;
CDS_SEC"1"
WATTAGE"1/16W"
PACK_TYPE"0402"
VALUE"100.0"
LOCATION"R1C4"
TOLERANCE"1%"
PART_NUMBER"G21796-017"
MATERIAL"CHIP"
CDS_LIB"mstr_discrete"
CDS_LOCATION"R1C4"
ROOM"PVSA_CPU1_VSENSE_VR"
BOM_COST"PROC_VRD_VCCIN_CPU0"
SEC_TYPE"0402"
SEC"1";
"B"
$PN"2"4;
"A"
$PN"1"19;
%"RES"
"2","(-5950,1725)","0","mstr_discrete","I34";
;
CDS_SEC"1"
VALUE"1.00K"
WATTAGE"1/16W"
TOLERANCE"1%"
LOCATION"R1C6"
MATERIAL"EMPTY"
PART_NUMBER"G21796-026"
PACK_TYPE"0402"
CDS_LIB"mstr_discrete"
CDS_LOCATION"R1C6"
ROOM"PVSA_CPU1_VSENSE_VR"
BOM_COST"PROC_VRD_VCCIN_CPU0"
NO_XNET_CONNECTION"1"
SEC"1"
SEC_TYPE"0402";
"A"
$PN"1"22;
"B"
$PN"2"19;
%"CAP"
"1","(-6625,3825)","0","mstr_discrete","I35";
;
CDS_SEC"1"
PACK_TYPE"0805"
PART_NUMBER"C95333-007"
MATERIAL"X6S"
TOLERANCE"10%"
LOCATION"C9N13"
VALUE"10UF"
VOLTAGE"16V"
CDS_LIB"mstr_discrete"
ROOM"PVSA_CPU1_PWR_VR"
CDS_LOCATION"C9N13"
SEC"1"
SEC_TYPE"0805";
"A"
$PN"1"3;
"B"
$PN"2"5;
%"CAP"
"1","(-6900,3850)","0","mstr_discrete","I36";
;
CDS_SEC"1"
VALUE"10UF"
VOLTAGE"16V"
PART_NUMBER"C95333-007"
PACK_TYPE"0805"
LOCATION"C9N19"
TOLERANCE"10%"
MATERIAL"X6S"
ROOM"PVSA_CPU1_PWR_VR"
SEC_TYPE"0805"
SEC"1"
CDS_LOCATION"C9N19"
CDS_LIB"mstr_discrete";
"A"
$PN"1"3;
"B"
$PN"2"5;
%"CAP"
"1","(-7175,3850)","0","mstr_discrete","I38";
;
CDS_SEC"1"
LOCATION"C9N21"
PACK_TYPE"0805"
VOLTAGE"16V"
TOLERANCE"10%"
VALUE"10UF"
MATERIAL"X6S"
PART_NUMBER"C95333-007"
CDS_LIB"mstr_discrete"
CDS_LOCATION"C9N21"
ROOM"PVSA_CPU1_PWR_VR"
SEC_TYPE"0805"
SEC"1";
"A"
$PN"1"3;
"B"
$PN"2"5;
%"GND"
"1","(-7175,3425)","0","mstr_symbols","I39";
;
VOLTAGE"0"
CDS_LIB"mstr_symbols"
SIZE"1B"
BOM_COST"PROC_VRD_VCCIN_CPU0"
ROOM"PVSA_CPU1_PWR_VR"
BODY_TYPE"PLUMBING"
HDL_POWER"GND";
"A\NAC"5;
%"P5V_STBY"
"1","(-4825,4575)","0","mstr_symbols","I42";
;
VOLTAGE"5.0V"
CDS_LIB"mstr_symbols"
SIZE"1B"
BODY_TYPE"PLUMBING"
HDL_POWER"P5V_STBY";
"G\NAC"6;
%"CAP_A"
"1","(-1000,3100)","0","dev_discrete","I44";
;
PART_NUMBER"E15431-004"
PACK_TYPE"0603V"
MATERIAL"X6S"
VOLTAGE"4V"
TOLERANCE"20%"
VALUE"22.0UF"
LOCATION"C9N22"
GROUP"PWR_MLCC_CAP"
CDS_LIB"dev_discrete"
SEC"1"
SEC_TYPE"0603V"
CDS_SEC"1"
CDS_LOCATION"C9N22";
"B"
$PN"2"14;
"A"
$PN"1"13;
%"RES"
"2","(-650,3100)","0","mstr_discrete","I45";
;
CDS_SEC"1"
PART_NUMBER"G21796-208"
PACK_TYPE"0402"
LOCATION"R9N4"
VALUE"51.1"
WATTAGE"1/16W"
MATERIAL"CHIP"
TOLERANCE"1.0%"
CDS_LOCATION"R9N4"
CDS_LIB"mstr_discrete"
SEC"1"
SEC_TYPE"0402";
"A"
$PN"1"13;
"B"
$PN"2"14;
%"PVSA_CPU1"
"1","(-4575,2500)","0","mstr_symbols","I46";
;
VOLTAGE"1.1V"
CDS_LIB"mstr_symbols"
BOM_COST"PROC_VRD_VCCIN_CPU0"
ROOM"PVSA_CPU1_PWR_VR"
BODY_TYPE"PLUMBING"
HDL_POWER"PVSA_CPU1";
"G\NAC"7;
%"PVSA_CPU1"
"1","(-1900,1700)","0","mstr_symbols","I47";
;
BOM_COST"PROC_VRD_VCCIN_CPU0"
ROOM"PVSA_CPU1_PWR_VR"
CDS_LIB"mstr_symbols"
VOLTAGE"1.1V"
BODY_TYPE"PLUMBING"
HDL_POWER"PVSA_CPU1";
"G\NAC"8;
%"IR354XX"
"1","(-3725,3600)","0","mstr_discrete","I51";
;
CDS_SEC"1"
PART_NUMBER"H73684-001"
MATERIAL"IC"
LOCATION"EU1C1"
CDS_LOCATION"EU1C1"
SEC"1"
SEC_TYPE"SM"
PACK_TYPE"SM"
CDS_LIB"mstr_discrete"
VALUE"IR35412";
"TOUT_FLT"
$PN"36"29;
"NC"
$PN"31"0;
"OCSET"
$PN"37"27;
"IOUT"
$PN"38"28;
"SW"
$PN"10"15;
"BOOST"
$PN"33"25;
"REFIN"
$PN"39"24;
"PWM"
$PN"34"30;
"PHASE"
$PN"32"26;
"VIN<0>"
$PN"25"3;
"VCC"
$PN"3"18;
"VIN<1>"
$PN"30"3;
"EN"
$PN"35"6;
"VDRV"
$PN"4"6;
"VOS"
$PN"1"13;
"LGND"
$PN"2"2;
"PGND<1>"
$PN"7"2;
"PGND<2>"
$PN"40"2;
"PGND<0>"
$PN"5"2;
"GL<0>"
$PN"6"16;
"GL<1>"
$PN"41"17;
%"RES"
"2","(-1450,3775)","0","mstr_discrete","I52";
;
CDS_LOCATION"R1C37"
PACK_TYPE"0402"
PART_NUMBER"G21796-187"
MATERIAL"EMPTY"
WATTAGE"1/16W"
TOLERANCE"1%"
VALUE"68.1K"
LOCATION"R1C37"
CDS_LIB"mstr_discrete"
CDS_SEC"1"
$SEC"1";
"A"
$PN"1"27;
"B"
$PN"2"9;
%"GND"
"1","(-1450,3600)","0","mstr_symbols","I53";
;
ROOM"PVSA_CPU1_PWR_VR"
BOM_COST"PROC_VRD_VCCIN_CPU0"
CDS_LIB"mstr_symbols"
SIZE"1B"
VOLTAGE"0"
BODY_TYPE"PLUMBING"
HDL_POWER"GND";
"A\NAC"9;
%"GND"
"1","(-4450,2850)","0","mstr_symbols","I54";
;
ROOM"PVCCIN_CPU0_PWR_VR"
BOM_COST"PROC_VRD_VCCIN_CPU0"
SIZE"1B"
VOLTAGE"0"
CDS_LIB"mstr_symbols"
BODY_TYPE"PLUMBING"
HDL_POWER"GND";
"A\NAC"10;
%"CAP_A"
"1","(-4450,3100)","0","dev_discrete","I55";
;
CDS_SEC"1"
CDS_LOCATION"CT57"
PART_NUMBER"A36096-030"
TOLERANCE"10%"
VOLTAGE"16V"
VALUE"0.1UF"
LOCATION"CT57"
PACK_TYPE"0402V"
POP"NOPOP"
MATERIAL"X7R"
SEC_TYPE"0402V"
SEC"1"
ROOM"PVCCIN_CPU0_PWR_VR"
CDS_LIB"dev_discrete";
"B"
$PN"2"10;
"A"
$PN"1"24;
%"GND"
"1","(-2500,2600)","0","mstr_symbols","I58";
;
SIZE"1B"
VOLTAGE"0"
BOM_COST"PROC_VRD_VCCIN_CPU0"
ROOM"PVCCIN_CPU0_PWR_VR"
CDS_LIB"mstr_symbols"
BODY_TYPE"PLUMBING"
HDL_POWER"GND";
"A\NAC"11;
%"CAP"
"1","(-2650,3625)","0","mstr_discrete","I60";
;
CDS_SEC"1"
CDS_LOCATION"CT55"
POP"NOPOP"
VALUE"1000PF"
TOLERANCE"10%"
MATERIAL"X7R"
PART_NUMBER"A36096-046"
VOLTAGE"50V"
LOCATION"CT55"
PACK_TYPE"0402LF"
SEC_TYPE"0402LF"
SEC"1"
CDS_LIB"mstr_discrete"
ROOM"VDDQ_KLM_PWR_VR";
"A"
$PN"1"29;
"B"
$PN"2"12;
%"GND"
"1","(-2650,3425)","0","mstr_symbols","I61";
;
SIZE"1B"
VOLTAGE"0"
ROOM"VDDQ_KLM_PWR_VR"
CDS_LIB"mstr_symbols"
BODY_TYPE"PLUMBING"
HDL_POWER"GND";
"A\NAC"12;
%"CAP"
"1","(-2500,3150)","0","mstr_discrete","I66";
;
CDS_SEC"1"
CDS_LOCATION"CT56"
TOLERANCE"10%"
VOLTAGE"50V"
PART_NUMBER"A36096-046"
VALUE"1000PF"
PACK_TYPE"0402LF"
MATERIAL"X7R"
LOCATION"CT56"
POP"NOPOP"
SEC_TYPE"0402LF"
SEC"1"
ROOM"VDDQ_KLM_PWR_VR"
CDS_LIB"mstr_discrete";
"A"
$PN"1"15;
"B"
$PN"2"31;
%"RES"
"1","(-5400,3375)","0","mstr_discrete","I68";
;
CDS_SEC"1"
CDS_LOCATION"RT37"
WATTAGE"1/10W"
MATERIAL"CHIP"
PACK_TYPE"0603"
PART_NUMBER"G22178-002"
TOLERANCE"5.0%"
LOCATION"RT37"
VALUE"0"
SEC_TYPE"0603"
SEC"1"
ROOM"NIC_SPRV"
BOM_COST"NT_GBE_BASE"
CDS_LIB"mstr_discrete";
"B"
$PN"2"25;
"A"
$PN"1"21;
%"PVSA_CPU1"
"1","(-650,3400)","0","mstr_symbols","I7";
;
CDS_LIB"mstr_symbols"
VOLTAGE"1.1V"
BODY_TYPE"PLUMBING"
HDL_POWER"PVSA_CPU1";
"G\NAC"13;
%"RES"
"1","(-5725,4425)","0","mstr_discrete","I71";
;
VALUE"0.0"
TOLERANCE"5%"
PART_NUMBER"G21497-005"
LOCATION"R9N3"
PACK_TYPE"0402"
MATERIAL"CHIP"
WATTAGE"1/16W"
BOM_COST"PROC_SIDEBAND"
CDS_LIB"mstr_discrete"
SEC_TYPE"0402"
SEC"1"
ROOM"CPU0"
CDS_SEC"1"
CDS_LOCATION"R9N3";
"B"
$PN"2"6;
"A"
$PN"1"18;
%"IND-300NH-20-GP"
"1","(-1625,3325)","1","w_hdl","I72";
;
CDS_SEC"1"
CDS_LOCATION"L1C1"
VALUE"IND-300NH-20-GP"
LOCATION"L1C1"
ATTRIBUTE"300NH"
RATED"ISAT=33A@25C"
PACK_SIZE"DCR=0.17MOHM"
TYPE"IRMS=66A@DELTA_T<40C"
PACK_TYPE"DISCRET-GB1"
SEC"1"
SEC_TYPE"DISCRET-GB1"
CDS_LMAN_SYM_OUTLINE"-75,100,75,-100"
CDS_LIB"w_hdl"
PART_NUMBER"068.3012N.M001";
"F"
$PN"2"13;
"S"
$PN"1"15;
%"SC1U10V2KX-4-GP"
"1","(-5475,3850)","0","w_hdl","I73";
;
CDS_SEC"1"
CDS_LOCATION"C1C3"
RATED"10V"
TOLERANCE"10%"
PACK_SIZE"0402"
ATTRIBUTE"1UF"
VALUE"SC1U10V2KX-4-GP"
LOCATION"C1C3"
SEC_TYPE"SMD-BCG6"
SEC"1"
PACK_TYPE"SMD-BCG6"
CDS_LMAN_SYM_OUTLINE"-50,25,50,-25"
CDS_LIB"w_hdl"
PART_NUMBER"78.10523.8FL";
"2"
$PN"2"5;
"1"
$PN"1"6;
%"1R3F-GP"
"1","(-2500,2825)","0","w_hdl","I74";
;
CDS_SEC"1"
CDS_LOCATION"RT38"
LOCATION"RT38"
VALUE"1R3F-GP"
ATTRIBUTE"1 OHM"
TOLERANCE"1%"
RATED"1/10W"
POP"NOPOP"
PACK_SIZE"0603"
PACK_TYPE"RCL_GP"
SEC"1"
SEC_TYPE"RCL_GP"
PART_NUMBER"64.1R005.55L"
CDS_LIB"w_hdl"
CDS_LMAN_SYM_OUTLINE"-50,75,50,-75";
"2"
$PN"2"11;
"1"
$PN"1"31;
%"CAP_A"
"1","(-1300,3100)","0","dev_discrete","I8";
;
PACK_TYPE"0603V"
PART_NUMBER"E15431-004"
MATERIAL"X6S"
VOLTAGE"4V"
VALUE"22.0UF"
LOCATION"C1C19"
TOLERANCE"20%"
GROUP"PWR_MLCC_CAP"
CDS_LIB"dev_discrete"
CDS_LOCATION"C1C19"
ROOM"PVSA_CPU1_PWR_VR"
BOM_COST"PROC_VRD_VCCIN_CPU0"
CDS_SEC"1"
SEC_TYPE"0603V"
SEC"1";
"B"
$PN"2"14;
"A"
$PN"1"13;
%"GND"
"1","(-650,2825)","0","mstr_symbols","I9";
;
SIZE"1B"
VOLTAGE"0"
CDS_LIB"mstr_symbols"
BOM_COST"PROC_VRD_VCCIN_CPU0"
ROOM"PVSA_CPU1_PWR_VR"
BODY_TYPE"PLUMBING"
HDL_POWER"GND";
"A\NAC"14;
END.
